# S9S_MB_2U (Grand Teton) — schematic netlist excerpt (pin names and nets, part order shuffled) for the footprints in the layout excerpt that follows; sources: Cadence DE-HDL packaged netlist, KiCad conversion of 03242023_DA0F0TMBIJ0_F0T_Motherboard_J_brd_V01_OCP.brd

C108  Q_CAP  10UF 6.3V 20% X6S  pkg C0603  page 210 : A = P3V3_AUX_CLK_GEN_VDD_CK440 ; B = GND
PC1370  Q_CAP  0.1UF 25V 10% X7R  pkg 0402  page 290 : A = GND ; B = PVCCIN_CPU1_VREF

(kicad_pcb
	(version 20260206)
	(generator "pcbnew")
	(generator_version "10.0")
	(general
		(thickness 1.6)
		(legacy_teardrops no)
	)
	(paper "A4")
	(title_block
		(title "03242023_DA0F0TMBIJ0_F0T_Motherboard_J_brd_V01_OCP.brd")
		(comment 1 "Grand Teton / footprints 472-473 of 6105")
	)
	(layers
		(0 "F.Cu" signal "TOP")
		(4 "In1.Cu" signal "GND")
		(6 "In2.Cu" signal "IN1")
		(8 "In3.Cu" signal "GND1")
		(10 "In4.Cu" signal "IN2")
		(12 "In5.Cu" signal "GND2")
		(14 "In6.Cu" signal "IN3")
		(16 "In7.Cu" signal "GND3")
		(18 "In8.Cu" signal "VCC")
		(20 "In9.Cu" signal "VCC1")
		(22 "In10.Cu" signal "GND4")
		(24 "In11.Cu" signal "IN4")
		(26 "In12.Cu" signal "GND5")
		(28 "In13.Cu" signal "IN5")
		(30 "In14.Cu" signal "GND6")
		(32 "In15.Cu" signal "IN6")
		(34 "In16.Cu" signal "GND7")
		(2 "B.Cu" signal "BOTTOM")
		(9 "F.Adhes" user "F.Adhesive")
		(11 "B.Adhes" user "B.Adhesive")
		(13 "F.Paste" user "Package Geometry/Pastemask Top")
		(15 "B.Paste" user "Package Geometry/Pastemask Bottom")
		(5 "F.SilkS" user "Ref Des/Silkscreen Top")
		(7 "B.SilkS" user "Ref Des/Silkscreen Bottom")
		(1 "F.Mask" user "Board Geometry/Soldermask Top")
		(3 "B.Mask" user "Board Geometry/Soldermask Bottom")
		(17 "Dwgs.User" user "User.Drawings")
		(19 "Cmts.User" user "User.Comments")
		(21 "Eco1.User" user "User.Eco1")
		(23 "Eco2.User" user "User.Eco2")
		(25 "Edge.Cuts" user "Board Geometry/Outline")
		(27 "Margin" user)
		(31 "F.CrtYd" user "Package Geometry/Place Bound Top")
		(29 "B.CrtYd" user "Package Geometry/Place Bound Bottom")
		(35 "F.Fab" user "Ref Des/Assembly Top")
		(33 "B.Fab" user "Ref Des/Assembly Bottom")
	)
	(footprint ""
		(layer "F.Cu")
		(at 263.542526 -94.888558)
		(property "Reference" "C108"
			(at 0 0 0)
			(layer "F.SilkS")
			(hide yes)
			(effects
				(font
					(size 1.27 1.27)
				)
			)
		)
		(property "Value" ""
			(at 0 0 0)
			(layer "F.Fab")
			(effects
				(font
					(size 1.27 1.27)
				)
			)
		)
		(duplicate_pad_numbers_are_jumpers no)
		(fp_line
			(start -1.2954 -0.5842)
			(end 1.2954 -0.5842)
			(stroke
				(width 0.1524)
				(type default)
			)
			(layer "F.SilkS")
		)
		(fp_line
			(start -1.2954 0.5842)
			(end -1.2954 -0.5842)
			(stroke
				(width 0.1524)
				(type default)
			)
			(layer "F.SilkS")
		)
		(fp_line
			(start 0 -0.5842)
			(end 0 0.5842)
			(stroke
				(width 0.1524)
				(type default)
			)
			(layer "F.SilkS")
		)
		(fp_line
			(start 1.2954 -0.5842)
			(end 1.2954 0.5842)
			(stroke
				(width 0.1524)
				(type default)
			)
			(layer "F.SilkS")
		)
		(fp_line
			(start 1.2954 0.5842)
			(end -1.2954 0.5842)
			(stroke
				(width 0.1524)
				(type default)
			)
			(layer "F.SilkS")
		)
		(fp_line
			(start -1.1938 -0.4064)
			(end -0.8636 -0.4064)
			(stroke
				(width 0.1)
				(type default)
			)
			(layer "F.Fab")
		)
		(fp_line
			(start -1.1938 0.4064)
			(end -1.1938 -0.4064)
			(stroke
				(width 0.1)
				(type default)
			)
			(layer "F.Fab")
		)
		(fp_line
			(start -0.8636 -0.4572)
			(end 0.8636 -0.4572)
			(stroke
				(width 0.1)
				(type default)
			)
			(layer "F.Fab")
		)
		(fp_line
			(start -0.8636 -0.4064)
			(end -0.8636 -0.4572)
			(stroke
				(width 0.1)
				(type default)
			)
			(layer "F.Fab")
		)
		(fp_line
			(start -0.8636 0.4064)
			(end -1.1938 0.4064)
			(stroke
				(width 0.1)
				(type default)
			)
			(layer "F.Fab")
		)
		(fp_line
			(start -0.8636 0.4572)
			(end -0.8636 0.4064)
			(stroke
				(width 0.1)
				(type default)
			)
			(layer "F.Fab")
		)
		(fp_line
			(start 0.8636 -0.4572)
			(end 0.8636 -0.4064)
			(stroke
				(width 0.1)
				(type default)
			)
			(layer "F.Fab")
		)
		(fp_line
			(start 0.8636 -0.4064)
			(end 1.1938 -0.4064)
			(stroke
				(width 0.1)
				(type default)
			)
			(layer "F.Fab")
		)
		(fp_line
			(start 0.8636 0.4064)
			(end 0.8636 0.4572)
			(stroke
				(width 0.1)
				(type default)
			)
			(layer "F.Fab")
		)
		(fp_line
			(start 0.8636 0.4572)
			(end -0.8636 0.4572)
			(stroke
				(width 0.1)
				(type default)
			)
			(layer "F.Fab")
		)
		(fp_line
			(start 1.1938 -0.4064)
			(end 1.1938 0.4064)
			(stroke
				(width 0.1)
				(type default)
			)
			(layer "F.Fab")
		)
		(fp_line
			(start 1.1938 0.4064)
			(end 0.8636 0.4064)
			(stroke
				(width 0.1)
				(type default)
			)
			(layer "F.Fab")
		)
		(pad "1" smd rect
			(at -0.7366 0 270)
			(size 0.7112 0.8128)
			(layers "F.Cu" "F.Mask" "F.Paste")
			(net "P3V3_AUX_CLK_GEN_VDD_CK440")
		)
		(pad "2" smd rect
			(at 0.7366 0 270)
			(size 0.7112 0.8128)
			(layers "F.Cu" "F.Mask" "F.Paste")
			(net "GND")
		)
	)
	(footprint ""
		(layer "F.Cu")
		(at 38.812724 -358.129586 -90)
		(property "Reference" "PC1370"
			(at 0 0 270)
			(layer "F.SilkS")
			(hide yes)
			(effects
				(font
					(size 1.27 1.27)
				)
			)
		)
		(property "Value" ""
			(at 0 0 270)
			(layer "F.Fab")
			(effects
				(font
					(size 1.27 1.27)
				)
			)
		)
		(duplicate_pad_numbers_are_jumpers no)
		(fp_line
			(start -0.7874 0.4064)
			(end -0.7874 -0.4064)
			(stroke
				(width 0.1524)
				(type default)
			)
			(layer "F.SilkS")
		)
		(fp_line
			(start 0.7874 0.4064)
			(end -0.7874 0.4064)
			(stroke
				(width 0.1524)
				(type default)
			)
			(layer "F.SilkS")
		)
		(fp_line
			(start -0.7874 -0.4064)
			(end 0.7874 -0.4064)
			(stroke
				(width 0.1524)
				(type default)
			)
			(layer "F.SilkS")
		)
		(fp_line
			(start 0.7874 -0.4064)
			(end 0.7874 0.4064)
			(stroke
				(width 0.1524)
				(type default)
			)
			(layer "F.SilkS")
		)
		(fp_line
			(start -0.67945 0.3048)
			(end -0.67945 -0.305054)
			(stroke
				(width 0.1)
				(type default)
			)
			(layer "F.Fab")
		)
		(fp_line
			(start -0.12065 0.3048)
			(end -0.67945 0.3048)
			(stroke
				(width 0.1)
				(type default)
			)
			(layer "F.Fab")
		)
		(fp_line
			(start 0.120396 0.3048)
			(end 0.120396 0.2794)
			(stroke
				(width 0.1)
				(type default)
			)
			(layer "F.Fab")
		)
		(fp_line
			(start 0.67945 0.3048)
			(end 0.120396 0.3048)
			(stroke
				(width 0.1)
				(type default)
			)
			(layer "F.Fab")
		)
		(fp_line
			(start -0.12065 0.2794)
			(end -0.12065 0.3048)
			(stroke
				(width 0.1)
				(type default)
			)
			(layer "F.Fab")
		)
		(fp_line
			(start 0.120396 0.2794)
			(end -0.12065 0.2794)
			(stroke
				(width 0.1)
				(type default)
			)
			(layer "F.Fab")
		)
		(fp_line
			(start -0.12065 -0.2794)
			(end 0.12065 -0.2794)
			(stroke
				(width 0.1)
				(type default)
			)
			(layer "F.Fab")
		)
		(fp_line
			(start 0.12065 -0.2794)
			(end 0.12065 -0.3048)
			(stroke
				(width 0.1)
				(type default)
			)
			(layer "F.Fab")
		)
		(fp_line
			(start 0.12065 -0.3048)
			(end 0.67945 -0.3048)
			(stroke
				(width 0.1)
				(type default)
			)
			(layer "F.Fab")
		)
		(fp_line
			(start 0.67945 -0.3048)
			(end 0.67945 0.3048)
			(stroke
				(width 0.1)
				(type default)
			)
			(layer "F.Fab")
		)
		(fp_line
			(start -0.67945 -0.305054)
			(end -0.12065 -0.305054)
			(stroke
				(width 0.1)
				(type default)
			)
			(layer "F.Fab")
		)
		(fp_line
			(start -0.12065 -0.305054)
			(end -0.12065 -0.2794)
			(stroke
				(width 0.1)
				(type default)
			)
			(layer "F.Fab")
		)
		(pad "1" smd circle
			(at -0.40005 0 270)
			(size 0 0)
			(layers "F.Cu" "F.Mask" "F.Paste")
			(net "GND")
		)
		(pad "2" smd circle
			(at 0.40005 0 270)
			(size 0 0)
			(layers "F.Cu" "F.Mask" "F.Paste")
			(net "PVCCIN_CPU1_VREF")
		)
	)
)
